FILE_TYPE = CONNECTIVITY;
{Allegro Design Entry HDL 17.2-2016 S081 (4005846) 1/11/2022}
"PAGE_NUMBER" = 143;
0"NC";
1"P3V3_STBY\g";
2"GND\g";
3"GND\g";
4"P3V3_STBY\g";
5"P3V3_STBY\g";
6"GND\g";
7"GND\g";
8"GND\g";
9"GND\g";
10"GND\g";
11"GND\g";
12"P3V3_STBY\g";
13"P5V_STBY\g";
14"P5V_STBY\g";
15"GND\g";
16"GND\g";
17"GND\g";
18"GND\g";
19"GND\g";
20"GND\g";
21"P3V3_STBY\g";
22"P3V3_STBY\g";
23"P1V8_STBY\g";
24"P1V8_STBY\g";
25"P3V3_STBY\g";
26"GND\g";
27"P3V3_STBY\g";
28"GND\g";
29"LED_D4";
30"FM_LED_D5";
31"LED_D6";
32"LED_D7";
33"LED_D6_R";
34"LED_D5";
35"LED_D0_R";
36"LED_D1_R";
37"LED_D0";
38"LED_D7_R";
39"LED_D5_R";
40"FM_LED_D3";
41"FM_LED_D4";
42"LED_D2";
43"FM_LED_D1";
44"FM_LED_D2";
45"LED_D3_R";
46"LED_D1";
47"LED_D4_R";
48"FM_LED_D7";
49"LED_D3";
50"LED_D2_R";
51"PU_BOOT_RDY_LED";
52"PU_SMERR_LED";
53"PU_P12V_ALL_PWROK_LED";
54"P5V_STBY_PWR_LED";
55"SMERR_LED_N";
56"BOOT_RDY_LED_N";
57"BOOT_RDY_BUF_LED";
58"BOOT_RDY_LED";
59"BOOT_RDY_R1_N";
60"P12V_ALL_PWROK_N";
61"P12V_ALL_PWROK";
62"FM_SMERR_BUF_LED_N";
63"FM_BIOS_POST_CMPLT_N";
64"BOOT_RDY_H";
65"BOOT_RDY_BUF_R_LED";
66"FM_SMERR_BUF_R_LED_N";
67"FM_SMERR_LED_N";
68"SMERR_LED";
69"FM_LED_D0";
70"FM_LED_D6";
%"UNIVERSAL_POWER"
"1","(-1875,5725)","0","pure_quanta_power","I1";
;
HDL_POWER"P3V3_STBY"
CDS_LIB"pure_quanta_power"
BOM_COST"OCP3.0 ";
"A"21;
%"UNIVERSAL_POWER"
"1","(-4100,4150)","0","pure_quanta_power","I10";
;
HDL_POWER"P3V3_STBY"
CDS_LIB"pure_quanta_power"
BOM_COST"OCP3.0 ";
"A"1;
%"Q_RES"
"2","(-4100,3800)","0","pure_quanta","I11";
;
LOCATION"R947"
$SEC"1"
CDS_SEC"1"
VALUE"4.7K"
TOLERANCE"5%"
MATERIAL"CHIP"
WATTAGE"1/16W"
PACK_TYPE"0402LF"
PART_NUMBER"TMP_QCS24702JB38"
BOM_COST"OCP3.0 "
CDS_LIB"pure_quanta";
"A"
$PN"1"1;
"B"
$PN"2"68;
%"GND"
"1","(-4150,3550)","1","pure_quanta_power","I12";
;
HDL_POWER"GND"
CDS_LIB"pure_quanta_power"
BOM_COST"MEM"
SIZE"1B";
"A<SIZE-1..0>\NAC"2;
%"GND"
"1","(-4775,5175)","5","pure_quanta_power","I13";
;
HDL_POWER"GND"
CDS_LIB"pure_quanta_power"
SIZE"1B"
BOM_COST"MEM";
"A<SIZE-1..0>\NAC"3;
%"UNIVERSAL_POWER"
"1","(-4950,5775)","0","pure_quanta_power","I14";
;
HDL_POWER"P3V3_STBY"
CDS_LIB"pure_quanta_power"
BOM_COST"OCP3.0 ";
"A"4;
%"Q_RES"
"2","(-4950,5425)","0","pure_quanta","I15";
;
LOCATION"R944"
$SEC"1"
CDS_SEC"1"
VALUE"4.7K"
TOLERANCE"5%"
MATERIAL"CHIP"
WATTAGE"1/16W"
PACK_TYPE"0402LF"
PART_NUMBER"TMP_QCS24702JB38"
BOM_COST"OCP3.0 "
CDS_LIB"pure_quanta";
"A"
$PN"1"4;
"B"
$PN"2"57;
%"MOSFET_DUAL_6P"
"1","(-4400,5125)","0","pure_quanta","I16";
;
LOCATION"Q2"
$SEC"1"
CDS_SEC"1"
PART_NUMBER"BAM70020047"
VALUE"2N7002KDW"
MATERIAL"IC"
PART_TYPE"SMLF"
NEEDS_NO_SIZE"TRUE"
CDS_LMAN_SYM_OUTLINE"-150,100,150,-100"
CDS_LIB"pure_quanta";
"D2"
$PN"3"56;
"D1"
$PN"6"58;
"S2"
$PN"4"16;
"S1"
$PN"1"3;
"G2"
$PN"5"58;
"G1"
$PN"2"57;
%"UNIVERSAL_POWER"
"1","(-5100,4150)","0","pure_quanta_power","I17";
;
HDL_POWER"P3V3_STBY"
CDS_LIB"pure_quanta_power"
BOM_COST"OCP3.0 ";
"A"5;
%"Q_RES"
"2","(-5100,3800)","0","pure_quanta","I18";
;
LOCATION"R945"
$SEC"1"
CDS_SEC"1"
MATERIAL"CHIP"
VALUE"4.7K"
TOLERANCE"5%"
WATTAGE"1/16W"
PACK_TYPE"0402LF"
PART_NUMBER"TMP_QCS24702JB38"
BOM_COST"OCP3.0 "
CDS_LIB"pure_quanta";
"A"
$PN"1"5;
"B"
$PN"2"66;
%"MOSFET_DUAL_6P"
"1","(-4550,3500)","0","pure_quanta","I19";
;
LOCATION"Q11"
$SEC"1"
CDS_SEC"1"
PART_NUMBER"BAM70020047"
VALUE"2N7002KDW"
MATERIAL"IC"
PART_TYPE"SMLF"
NEEDS_NO_SIZE"TRUE"
CDS_LMAN_SYM_OUTLINE"-150,100,150,-100"
CDS_LIB"pure_quanta";
"D2"
$PN"3"55;
"D1"
$PN"6"68;
"S2"
$PN"4"2;
"S1"
$PN"1"6;
"G2"
$PN"5"68;
"G1"
$PN"2"66;
%"UNIVERSAL_POWER"
"1","(-2125,4100)","0","pure_quanta_power","I2";
;
HDL_POWER"P3V3_STBY"
CDS_LIB"pure_quanta_power"
BOM_COST"OCP3.0 ";
"A"22;
%"GND"
"1","(-4925,3550)","5","pure_quanta_power","I20";
;
HDL_POWER"GND"
CDS_LIB"pure_quanta_power"
SIZE"1B"
BOM_COST"MEM";
"A<SIZE-1..0>\NAC"6;
%"Q_RES"
"1","(-5675,5125)","0","pure_quanta","I21";
;
LOCATION"R935"
$SEC"1"
CDS_SEC"1"
VALUE"0"
ROOM"RST_CPU0_PLD_TO_DIMM"
PACK_TYPE"0402LF"
PART_NUMBER"CS00002JB38"
TOLERANCE"5%"
MATERIAL"CHIP"
WATTAGE"1/16W"
CDS_LIB"pure_quanta"
BOM_COST"MEM";
"B"
$PN"2"57;
"A"
$PN"1"65;
%"Q_RES"
"1","(-5825,3500)","0","pure_quanta","I22";
;
LOCATION"R936"
$SEC"1"
CDS_SEC"1"
VALUE"0"
ROOM"RST_CPU0_PLD_TO_DIMM"
PACK_TYPE"0402LF"
PART_NUMBER"CS00002JB38"
TOLERANCE"5%"
MATERIAL"CHIP"
WATTAGE"1/16W"
CDS_LIB"pure_quanta"
BOM_COST"MEM";
"B"
$PN"2"66;
"A"
$PN"1"62;
%"Q_CAP"
"1","(-7200,5450)","0","pure_quanta","I24";
;
LOCATION"C218"
$SEC"1"
CDS_SEC"1"
PACK_TYPE"0402"
VOLTAGE"25V"
PART_NUMBER"CH4104K1B00"
VALUE"0.1UF"
TOLERANCE"10%"
MATERIAL"X7R"
BOM_COST"OCP3.0 "
CDS_LIB"pure_quanta";
"B"
$PN"2"7;
"A"
$PN"1"24;
%"UNIVERSAL_GND"
"1","(-7200,5250)","0","pure_quanta_power","I25";
;
HDL_POWER"GND"
CDS_LIB"pure_quanta_power"
BOM_COST"OCP3.0 ";
"A"7;
%"SN74LVC1G07DBVR"
"1","(-6600,5125)","0","pure_quanta","I26";
;
LOCATION"U82"
$SEC"1"
CDS_SEC"1"
PACK_TYPE"SMLF"
PART_NUMBER"AL1G0007024"
VALUE"SN74LVC1G07DBVR"
MATERIAL"IC"
NEEDS_NO_SIZE"TRUE"
CDS_LIB"pure_quanta";
"NC"
$PN"1"0;
"Y"
$PN"4"65;
"GND"
$PN"3"8;
"A"
$PN"2"59;
"VCC"
$PN"5"24;
%"UNIVERSAL_GND"
"1","(-6850,4850)","0","pure_quanta_power","I27";
;
HDL_POWER"GND"
CDS_LIB"pure_quanta_power"
BOM_COST"OCP3.0 ";
"A"8;
%"P1V0"
"1","(-7350,4125)","0","pure_quanta_power","I28";
;
HDL_POWER"P1V8_STBY"
CDS_LIB"pure_quanta_power";
"A"23;
%"Q_CAP"
"1","(-7350,3825)","0","pure_quanta","I29";
;
LOCATION"C219"
$SEC"1"
CDS_SEC"1"
VALUE"0.1UF"
VOLTAGE"25V"
TOLERANCE"10%"
PACK_TYPE"0402"
PART_NUMBER"CH4104K1B00"
MATERIAL"X7R"
BOM_COST"OCP3.0 "
CDS_LIB"pure_quanta";
"B"
$PN"2"9;
"A"
$PN"1"23;
%"Q_RES"
"1","(-2250,3450)","0","pure_quanta","I3";
;
LOCATION"R950"
$SEC"1"
CDS_SEC"1"
PACK_TYPE"0402LF"
VALUE"200"
TOLERANCE"1%"
MATERIAL"CHIP"
WATTAGE"1/16W"
PART_NUMBER"CS12002FB06"
CDS_LIB"pure_quanta";
"B"
$PN"2"22;
"A"
$PN"1"52;
%"UNIVERSAL_GND"
"1","(-7350,3625)","0","pure_quanta_power","I30";
;
HDL_POWER"GND"
CDS_LIB"pure_quanta_power"
BOM_COST"OCP3.0 ";
"A"9;
%"SN74LVC1G07DBVR"
"1","(-6750,3500)","0","pure_quanta","I31";
;
LOCATION"U86"
$SEC"1"
CDS_SEC"1"
PACK_TYPE"SMLF"
PART_NUMBER"AL1G0007024"
VALUE"SN74LVC1G07DBVR"
MATERIAL"IC"
NEEDS_NO_SIZE"TRUE"
CDS_LIB"pure_quanta";
"NC"
$PN"1"0;
"Y"
$PN"4"62;
"GND"
$PN"3"10;
"A"
$PN"2"67;
"VCC"
$PN"5"23;
%"UNIVERSAL_GND"
"1","(-7000,3225)","0","pure_quanta_power","I32";
;
BOM_COST"OCP3.0 "
HDL_POWER"GND"
CDS_LIB"pure_quanta_power";
"A"10;
%"Q_RES"
"1","(-7950,5125)","0","pure_quanta","I33";
;
LOCATION"R934"
$SEC"1"
CDS_SEC"1"
VALUE"0"
ROOM"RST_CPU0_PLD_TO_DIMM"
PACK_TYPE"0402LF"
PART_NUMBER"CS00002JB38"
TOLERANCE"5%"
MATERIAL"CHIP"
WATTAGE"1/16W"
CDS_LIB"pure_quanta"
BOM_COST"MEM";
"B"
$PN"2"59;
"A"
$PN"1"63;
%"Q_RES"
"1","(-7950,4875)","0","pure_quanta","I34";
;
LOCATION"R941"
$SEC"1"
CDS_SEC"1"
VALUE"0"
MATERIAL"EMPTY"
PACK_TYPE"0402LF"
PART_NUMBER"CS00002JB38"
TOLERANCE"5%"
WATTAGE"1/16W"
CDS_LIB"pure_quanta";
"B"
$PN"2"59;
"A"
$PN"1"64;
%"Q_LED"
"1","(-4275,550)","2","pure_quanta","I38";
;
LOCATION"D49"
$SEC"1"
CDS_SEC"1"
PACK_TYPE"SMLF"
COLOR"LED_GREEN"
PART_NUMBER"BEGR0278Z00"
MATERIAL"IC"
MANUF_PN"19-213/GVC-AMNB/3T"
CDS_LIB"pure_quanta"
NEEDS_NO_SIZE"TRUE";
"A"
$PN"A"54;
"C"
$PN"C"11;
%"UNIVERSAL_GND"
"1","(-4750,375)","0","pure_quanta_power","I39";
;
HDL_POWER"GND"
BOM_COST"OCP3.0 "
CDS_LIB"pure_quanta_power";
"A"11;
%"UNIVERSAL_POWER"
"1","(-3950,5775)","0","pure_quanta_power","I4";
;
HDL_POWER"P3V3_STBY"
CDS_LIB"pure_quanta_power"
BOM_COST"OCP3.0 ";
"A"12;
%"P1V0"
"1","(-2725,975)","0","pure_quanta_power","I40";
;
HDL_POWER"P5V_STBY"
CDS_LIB"pure_quanta_power";
"A"13;
%"Q_RES"
"1","(-3275,550)","0","pure_quanta","I41";
;
LOCATION"R1207"
$SEC"1"
CDS_SEC"1"
PACK_TYPE"0603LF"
PART_NUMBER"CS13303F917"
VALUE"330"
TOLERANCE"1%"
MATERIAL"CHIP"
WATTAGE"1/10W"
CDS_LIB"pure_quanta";
"B"
$PN"2"13;
"A"
$PN"1"54;
%"Q_RES"
"1","(-3125,1975)","0","pure_quanta","I42";
;
LOCATION"R1208"
$SEC"1"
CDS_SEC"1"
PACK_TYPE"0603LF"
PART_NUMBER"CS13303F917"
VALUE"330"
TOLERANCE"1%"
MATERIAL"CHIP"
WATTAGE"1/10W"
CDS_LIB"pure_quanta";
"B"
$PN"2"14;
"A"
$PN"1"53;
%"Q_LED"
"1","(-4125,1975)","2","pure_quanta","I43";
;
LOCATION"D46"
$SEC"1"
CDS_SEC"1"
PACK_TYPE"SMLF"
COLOR"LED_GREEN"
PART_NUMBER"BEGR0278Z00"
MATERIAL"IC"
MANUF_PN"19-213/GVC-AMNB/3T"
NEEDS_NO_SIZE"TRUE"
CDS_LIB"pure_quanta";
"A"
$PN"A"53;
"C"
$PN"C"60;
%"MOSFET_N_GSD"
"1","(-4875,1625)","0","pure_quanta","I44";
;
LOCATION"Q12"
$SEC"1"
CDS_SEC"1"
PART_NUMBER"BAM01380023"
VALUE"NX138BK"
MATERIAL"IC"
PART_TYPE"SMLF"
NEEDS_NO_SIZE"TRUE"
CDS_LMAN_SYM_OUTLINE"-100,100,100,-100"
CDS_LIB"pure_quanta";
"DRAIN"
$PN"D"60;
"SOURCE"
$PN"S"15;
"GATE"
$PN"G"61;
%"P1V0"
"1","(-2550,2400)","0","pure_quanta_power","I45";
;
HDL_POWER"P5V_STBY"
CDS_LIB"pure_quanta_power";
"A"14;
%"UNIVERSAL_GND"
"1","(-4850,1300)","0","pure_quanta_power","I46";
;
HDL_POWER"GND"
CDS_LIB"pure_quanta_power"
BOM_COST"OCP3.0 ";
"A"15;
%"P1V0"
"1","(-7200,5750)","0","pure_quanta_power","I48";
;
HDL_POWER"P1V8_STBY"
CDS_LIB"pure_quanta_power";
"A"24;
%"Q_LED"
"1","(-7425,2825)","2","pure_quanta","I49";
;
$LOCATION"D1"
CDS_LOCATION"D1"
$SEC"1"
CDS_SEC"1"
PART_NUMBER"BEGR0278Z00"
MATERIAL"IC"
MANUF_PN"19-213/GVC-AMNB/3T"
COLOR"LED_GREEN"
PACK_TYPE"SMLF"
CDS_LIB"pure_quanta"
NEEDS_NO_SIZE"TRUE";
"A"
$PN"A"35;
"C"
$PN"C"37;
%"Q_RES"
"2","(-3950,5425)","0","pure_quanta","I5";
;
LOCATION"R946"
$SEC"1"
CDS_SEC"1"
VALUE"4.7K"
TOLERANCE"5%"
MATERIAL"CHIP"
WATTAGE"1/16W"
PACK_TYPE"0402LF"
PART_NUMBER"TMP_QCS24702JB38"
BOM_COST"OCP3.0 "
CDS_LIB"pure_quanta";
"A"
$PN"1"12;
"B"
$PN"2"58;
%"Q_LED"
"1","(-7425,2650)","2","pure_quanta","I50";
;
$LOCATION"D3"
CDS_LOCATION"D3"
$SEC"1"
CDS_SEC"1"
PART_NUMBER"BEGR0278Z00"
MATERIAL"IC"
MANUF_PN"19-213/GVC-AMNB/3T"
COLOR"LED_GREEN"
PACK_TYPE"SMLF"
CDS_LIB"pure_quanta"
NEEDS_NO_SIZE"TRUE";
"A"
$PN"A"36;
"C"
$PN"C"46;
%"Q_LED"
"1","(-7425,2450)","2","pure_quanta","I51";
;
$LOCATION"D10"
CDS_LOCATION"D10"
$SEC"1"
CDS_SEC"1"
PART_NUMBER"BEGR0278Z00"
MATERIAL"IC"
MANUF_PN"19-213/GVC-AMNB/3T"
COLOR"LED_GREEN"
PACK_TYPE"SMLF"
CDS_LIB"pure_quanta"
NEEDS_NO_SIZE"TRUE";
"A"
$PN"A"50;
"C"
$PN"C"42;
%"Q_LED"
"1","(-7425,2250)","2","pure_quanta","I52";
;
$LOCATION"D11"
CDS_LOCATION"D11"
$SEC"1"
CDS_SEC"1"
PART_NUMBER"BEGR0278Z00"
MATERIAL"IC"
MANUF_PN"19-213/GVC-AMNB/3T"
COLOR"LED_GREEN"
PACK_TYPE"SMLF"
CDS_LIB"pure_quanta"
NEEDS_NO_SIZE"TRUE";
"A"
$PN"A"45;
"C"
$PN"C"49;
%"P1V0"
"1","(-6425,3075)","0","pure_quanta_power","I53";
;
HDL_POWER"P3V3_STBY"
CDS_LIB"pure_quanta_power";
"A"25;
%"Q_RES"
"1","(-6750,2825)","0","pure_quanta","I54";
;
$LOCATION"R1075"
CDS_LOCATION"R1075"
$SEC"1"
CDS_SEC"1"
MATERIAL"CHIP"
VALUE"200"
PART_NUMBER"CS12002FB06"
PACK_TYPE"0402LF"
TOLERANCE"1%"
WATTAGE"1/16W"
CDS_LIB"pure_quanta";
"B"
$PN"2"25;
"A"
$PN"1"35;
%"Q_RES"
"1","(-6750,2650)","0","pure_quanta","I55";
;
$LOCATION"R1076"
CDS_LOCATION"R1076"
$SEC"1"
CDS_SEC"1"
PART_NUMBER"CS12002FB06"
MATERIAL"CHIP"
VALUE"200"
PACK_TYPE"0402LF"
TOLERANCE"1%"
WATTAGE"1/16W"
CDS_LIB"pure_quanta";
"B"
$PN"2"25;
"A"
$PN"1"36;
%"Q_RES"
"1","(-6750,2450)","0","pure_quanta","I56";
;
$LOCATION"R1102"
CDS_LOCATION"R1102"
$SEC"1"
CDS_SEC"1"
MATERIAL"CHIP"
VALUE"200"
PART_NUMBER"CS12002FB06"
WATTAGE"1/16W"
TOLERANCE"1%"
PACK_TYPE"0402LF"
CDS_LIB"pure_quanta";
"B"
$PN"2"25;
"A"
$PN"1"50;
%"Q_RES"
"1","(-6750,2250)","0","pure_quanta","I57";
;
$LOCATION"R1103"
CDS_LOCATION"R1103"
$SEC"1"
CDS_SEC"1"
PART_NUMBER"CS12002FB06"
VALUE"200"
MATERIAL"CHIP"
WATTAGE"1/16W"
TOLERANCE"1%"
PACK_TYPE"0402LF"
CDS_LIB"pure_quanta";
"B"
$PN"2"25;
"A"
$PN"1"45;
%"MOSFET_DUAL_6P"
"1","(-8550,2650)","6","pure_quanta","I58";
;
$LOCATION"Q32"
CDS_LOCATION"Q32"
$SEC"1"
CDS_SEC"1"
PART_NUMBER"BAM70020047"
MATERIAL"IC"
VALUE"2N7002KDW"
NEEDS_NO_SIZE"TRUE"
CDS_LIB"pure_quanta"
CDS_LMAN_SYM_OUTLINE"-150,100,150,-100"
PART_TYPE"SMLF";
"D2"
$PN"3"46;
"D1"
$PN"6"37;
"S2"
$PN"4"26;
"S1"
$PN"1"17;
"G2"
$PN"5"43;
"G1"
$PN"2"69;
%"GND"
"1","(-4000,5175)","1","pure_quanta_power","I6";
;
HDL_POWER"GND"
CDS_LIB"pure_quanta_power"
BOM_COST"MEM"
SIZE"1B";
"A<SIZE-1..0>\NAC"16;
%"UNIVERSAL_GND"
"1","(-8950,2475)","0","pure_quanta_power","I60";
;
HDL_POWER"GND"
BOM_COST"OCP3.0 "
CDS_LIB"pure_quanta_power";
"A"17;
%"MOSFET_DUAL_6P"
"1","(-8525,2200)","6","pure_quanta","I62";
;
$LOCATION"Q33"
CDS_LOCATION"Q33"
$SEC"1"
CDS_SEC"1"
PART_NUMBER"BAM70020047"
MATERIAL"IC"
VALUE"2N7002KDW"
NEEDS_NO_SIZE"TRUE"
CDS_LIB"pure_quanta"
CDS_LMAN_SYM_OUTLINE"-150,100,150,-100"
PART_TYPE"SMLF";
"D2"
$PN"3"49;
"D1"
$PN"6"42;
"S2"
$PN"4"26;
"S1"
$PN"1"18;
"G2"
$PN"5"40;
"G1"
$PN"2"44;
%"UNIVERSAL_GND"
"1","(-8075,1825)","0","pure_quanta_power","I64";
;
HDL_POWER"GND"
BOM_COST"OCP3.0 "
CDS_LIB"pure_quanta_power";
"A"26;
%"UNIVERSAL_GND"
"1","(-8925,2000)","0","pure_quanta_power","I67";
;
HDL_POWER"GND"
BOM_COST"OCP3.0 "
CDS_LIB"pure_quanta_power";
"A"18;
%"Q_LED"
"1","(-7400,925)","2","pure_quanta","I68";
;
$LOCATION"D32"
CDS_LOCATION"D32"
$SEC"1"
CDS_SEC"1"
MATERIAL"IC"
PART_NUMBER"BEGR0278Z00"
MANUF_PN"19-213/GVC-AMNB/3T"
COLOR"LED_GREEN"
PACK_TYPE"SMLF"
NEEDS_NO_SIZE"TRUE"
CDS_LIB"pure_quanta";
"A"
$PN"A"33;
"C"
$PN"C"31;
%"MOSFET_DUAL_6P"
"1","(-8500,675)","6","pure_quanta","I69";
;
$LOCATION"Q37"
CDS_LOCATION"Q37"
$SEC"1"
CDS_SEC"1"
PART_NUMBER"BAM70020047"
MATERIAL"IC"
CDS_LIB"pure_quanta"
CDS_LMAN_SYM_OUTLINE"-150,100,150,-100"
NEEDS_NO_SIZE"TRUE"
VALUE"2N7002KDW"
PART_TYPE"SMLF";
"D2"
$PN"3"32;
"D1"
$PN"6"31;
"S2"
$PN"4"28;
"S1"
$PN"1"20;
"G2"
$PN"5"48;
"G1"
$PN"2"70;
%"Q_RES"
"1","(-2000,5075)","0","pure_quanta","I7";
;
LOCATION"R948"
$SEC"1"
CDS_SEC"1"
PACK_TYPE"0402LF"
VALUE"200"
TOLERANCE"1%"
MATERIAL"CHIP"
WATTAGE"1/16W"
PART_NUMBER"CS12002FB06"
CDS_LIB"pure_quanta";
"B"
$PN"2"21;
"A"
$PN"1"51;
%"P1V0"
"1","(-6400,1550)","0","pure_quanta_power","I70";
;
HDL_POWER"P3V3_STBY"
CDS_LIB"pure_quanta_power";
"A"27;
%"Q_RES"
"1","(-6725,1300)","0","pure_quanta","I71";
;
$LOCATION"R1105"
CDS_LOCATION"R1105"
$SEC"1"
CDS_SEC"1"
MATERIAL"CHIP"
VALUE"200"
PART_NUMBER"CS12002FB06"
CDS_LIB"pure_quanta"
WATTAGE"1/16W"
TOLERANCE"1%"
PACK_TYPE"0402LF";
"B"
$PN"2"27;
"A"
$PN"1"47;
%"Q_RES"
"1","(-6725,1125)","0","pure_quanta","I72";
;
$LOCATION"R1106"
CDS_LOCATION"R1106"
$SEC"1"
CDS_SEC"1"
MATERIAL"CHIP"
PART_NUMBER"CS12002FB06"
VALUE"200"
CDS_LIB"pure_quanta"
WATTAGE"1/16W"
TOLERANCE"1%"
PACK_TYPE"0402LF";
"B"
$PN"2"27;
"A"
$PN"1"39;
%"Q_RES"
"1","(-6725,925)","0","pure_quanta","I73";
;
$LOCATION"R1127"
CDS_LOCATION"R1127"
$SEC"1"
CDS_SEC"1"
MATERIAL"CHIP"
VALUE"200"
PART_NUMBER"CS12002FB06"
CDS_LIB"pure_quanta"
PACK_TYPE"0402LF"
TOLERANCE"1%"
WATTAGE"1/16W";
"B"
$PN"2"27;
"A"
$PN"1"33;
%"Q_RES"
"1","(-6725,725)","0","pure_quanta","I74";
;
$LOCATION"R1128"
CDS_LOCATION"R1128"
$SEC"1"
CDS_SEC"1"
MATERIAL"CHIP"
PART_NUMBER"CS12002FB06"
VALUE"200"
CDS_LIB"pure_quanta"
PACK_TYPE"0402LF"
TOLERANCE"1%"
WATTAGE"1/16W";
"B"
$PN"2"27;
"A"
$PN"1"38;
%"Q_LED"
"1","(-7400,1300)","2","pure_quanta","I75";
;
$LOCATION"D12"
CDS_LOCATION"D12"
$SEC"1"
CDS_SEC"1"
PART_NUMBER"BEGR0278Z00"
MATERIAL"IC"
MANUF_PN"19-213/GVC-AMNB/3T"
COLOR"LED_GREEN"
PACK_TYPE"SMLF"
NEEDS_NO_SIZE"TRUE"
CDS_LIB"pure_quanta";
"A"
$PN"A"47;
"C"
$PN"C"29;
%"Q_LED"
"1","(-7400,1125)","2","pure_quanta","I76";
;
$LOCATION"D13"
CDS_LOCATION"D13"
$SEC"1"
CDS_SEC"1"
PART_NUMBER"BEGR0278Z00"
MATERIAL"IC"
MANUF_PN"19-213/GVC-AMNB/3T"
COLOR"LED_GREEN"
PACK_TYPE"SMLF"
NEEDS_NO_SIZE"TRUE"
CDS_LIB"pure_quanta";
"A"
$PN"A"39;
"C"
$PN"C"34;
%"Q_LED"
"1","(-7400,725)","2","pure_quanta","I77";
;
$LOCATION"D33"
CDS_LOCATION"D33"
$SEC"1"
CDS_SEC"1"
PART_NUMBER"BEGR0278Z00"
MATERIAL"IC"
MANUF_PN"19-213/GVC-AMNB/3T"
COLOR"LED_GREEN"
PACK_TYPE"SMLF"
NEEDS_NO_SIZE"TRUE"
CDS_LIB"pure_quanta";
"A"
$PN"A"38;
"C"
$PN"C"32;
%"UNIVERSAL_GND"
"1","(-8050,300)","0","pure_quanta_power","I78";
;
CDS_LIB"pure_quanta_power"
BOM_COST"OCP3.0 "
HDL_POWER"GND";
"A"28;
%"MOSFET_DUAL_6P"
"1","(-8525,1125)","6","pure_quanta","I79";
;
$LOCATION"Q34"
CDS_LOCATION"Q34"
$SEC"1"
CDS_SEC"1"
MATERIAL"IC"
PART_NUMBER"BAM70020047"
CDS_LIB"pure_quanta"
CDS_LMAN_SYM_OUTLINE"-150,100,150,-100"
NEEDS_NO_SIZE"TRUE"
VALUE"2N7002KDW"
PART_TYPE"SMLF";
"D2"
$PN"3"34;
"D1"
$PN"6"29;
"S2"
$PN"4"28;
"S1"
$PN"1"19;
"G2"
$PN"5"30;
"G1"
$PN"2"41;
%"Q_LED"
"1","(-2950,5075)","2","pure_quanta","I8";
;
LOCATION"D5"
$SEC"1"
CDS_SEC"1"
PACK_TYPE"SMLF"
COLOR"LED_GREEN"
PART_NUMBER"BEGR0278Z00"
MATERIAL"IC"
MANUF_PN"19-213/GVC-AMNB/3T"
NEEDS_NO_SIZE"TRUE"
CDS_LIB"pure_quanta";
"A"
$PN"A"51;
"C"
$PN"C"56;
%"UNIVERSAL_GND"
"1","(-8925,950)","0","pure_quanta_power","I80";
;
CDS_LIB"pure_quanta_power"
BOM_COST"OCP3.0 "
HDL_POWER"GND";
"A"19;
%"UNIVERSAL_GND"
"1","(-8900,475)","0","pure_quanta_power","I84";
;
CDS_LIB"pure_quanta_power"
BOM_COST"OCP3.0 "
HDL_POWER"GND";
"A"20;
%"Q_LED"
"1","(-3100,3450)","2","pure_quanta","I9";
;
LOCATION"D6"
$SEC"1"
CDS_SEC"1"
PACK_TYPE"SMLF"
COLOR"LED_RED"
PART_NUMBER"BERD0021Z02"
MATERIAL"IC"
MANUF_PN"LTST-C190KRKT"
NEEDS_NO_SIZE"TRUE"
CDS_LIB"pure_quanta";
"A"
$PN"A"52;
"C"
$PN"C"55;
END.
